FILE_TYPE = MULTI_PHYS_TABLE;

PART 'MOSFET_NCH_1D3S'

{========================================================================================}
:VALUE             | PART_TYPE | MATERIAL | PART_NUMBER    = STANDARD        | LIFECYCLE      | PART_NUMBER   | JEDEC_TYPE               | DESCRIPTION                                | MANUFTR | MANUF_PN          | RD_CMPLS_LVL | CMPLS_LVL | CLASS | DIP_SMD | FP_ECN | FROM_PJ         | DATA                             | EE_CHECK_LIST | STATUS | PSL | PREFERENCE | CREATOR | CREATEDAY  ;
{========================================================================================}
 'PH0925CL'        | 'SMLF'    | 'IC'     | 'BAM09250000'(!) = ''              | ''             | 'BAM09250000' |'SOT1023'| 'TRANS MOSFET PH0925CL(25V,100A,137W)'     | 'NXP'   | 'PH0925CL'        | 'EU(V1)'     | ''        | 'IC'  | ''      | ''     | 'F03R-RAYMOND'  | 'NXP_PH0925CL.pdf'               | ''            | ''     | ''  | ''         | ''      | '20120423'
 'PH0925CL'        | 'SMLF'    | 'EMPTY'  | 'BAM09250000'(!) = ''              | ''             | 'BAM09250000' |'SOT1023'| 'TRANS MOSFET PH0925CL(25V,100A,137W)'     | 'NXP'   | 'PH0925CL'        | 'EU(V1)'     | ''        | 'IC'  | ''      | ''     | 'F03R-RAYMOND'  | 'NXP_PH0925CL.pdf'               | ''            | ''     | ''  | ''         | ''      | '20120423'
 'PH1125CL'        | 'SMLF'    | 'IC'     | 'BAM11250001'(!) = 'Non-Preferred' | 'End of Life'  | 'BAM11250001' |'SOT1023_EOL'| 'TRANS MOSFET PH1125CL(25V,100A,215W)'     | 'NXP'   | 'PH1125CL'        | 'EU(V1)'     | ''        | 'IC'  | ''      | ''     | 'F03R-RAYMOND'  | 'NXP_PH1125CL.pdf'               | ''            | ''     | ''  | ''         | ''      | '20120423'
 'PH1125CL'        | 'SMLF'    | 'EMPTY'  | 'BAM11250001'(!) = 'Non-Preferred' | 'End of Life'  | 'BAM11250001' |'SOT1023_EOL'| 'TRANS MOSFET PH1125CL(25V,100A,215W)'     | 'NXP'   | 'PH1125CL'        | 'EU(V1)'     | ''        | 'IC'  | ''      | ''     | 'F03R-RAYMOND'  | 'NXP_PH1125CL.pdf'               | ''            | ''     | ''  | ''         | ''      | '20120423'
 'AON6524'         | 'SMLF'    | 'IC'     | 'BAM65240000'(!) = ''              | ''             | 'BAM65240000' |'SOIC8_PWXI'| 'TRANS MOSFET AON6524(30V,65A,5.6W)DFN5X6' | 'AOS'   | 'AON6524'         | 'EP(V1)'     | ''        | 'IC'  | ''      | ''     | 'S1N-KC'        | 'AOS_AON6524.pdf'                | ''            | ''     | ''  | ''         | ''      | '20120514'
 'AON6524'         | 'SMLF'    | 'EMPTY'  | 'BAM65240000'(!) = ''              | ''             | 'BAM65240000' |'SOIC8_PWXI'| 'TRANS MOSFET AON6524(30V,65A,5.6W)DFN5X6' | 'AOS'   | 'AON6524'         | 'EP(V1)'     | ''        | 'IC'  | ''      | ''     | 'S1N-KC'        | 'AOS_AON6524.pdf'                | ''            | ''     | ''  | ''         | ''      | '20120514'
 'AON6756'         | 'SMLF'    | 'IC'     | 'BAM67560000'(!) = 'End of Design' | 'End of Life'  | 'BAM67560000' |'SOIC8_PWXI_EOL'| 'TRANS MOSFET AON6756(30V,36A,7.3W)DFN5X6' | 'AOS'   | 'AON6756'         | 'EP(V1)'     | ''        | 'IC'  | ''      | ''     | 'S1N-KC'        | 'AOS_AON6756_rev0.pdf'           | ''            | ''     | ''  | ''         | ''      | '20120621'
 'AON6756'         | 'SMLF'    | 'EMPTY'  | 'BAM67560000'(!) = 'End of Design' | 'End of Life'  | 'BAM67560000' |'SOIC8_PWXI_EOL'| 'TRANS MOSFET AON6756(30V,36A,7.3W)DFN5X6' | 'AOS'   | 'AON6756'         | 'EP(V1)'     | ''        | 'IC'  | ''      | ''     | 'S1N-KC'        | 'AOS_AON6756_rev0.pdf'           | ''            | ''     | ''  | ''         | ''      | '20120621'
 'AP9440GYT-HF'    | 'SMLF'    | 'IC'     | 'BAM94400000'(!) = ''              | 'End of Life'  | 'BAM94400000' |'PMPAK5_3_EOL'| 'TRANS MOS AP9440GYT-HF(20V,20.8A,3.13W)'  | 'AVP'   | 'AP9440GYT-HF'    | 'EP(V1)'     | ''        | 'IC'  | ''      | ''     | 'LY1R-CARSON'   | 'AVP_AP9440GYT-HF.pdf'           | ''            | ''     | ''  | ''         | ''      | '20121115'
 'AP9440GYT-HF'    | 'SMLF'    | 'EMPTY'  | 'BAM94400000'(!) = ''              | 'End of Life'  | 'BAM94400000' |'PMPAK5_3_EOL'| 'TRANS MOS AP9440GYT-HF(20V,20.8A,3.13W)'  | 'AVP'   | 'AP9440GYT-HF'    | 'EP(V1)'     | ''        | 'IC'  | ''      | ''     | 'LY1R-CARSON'   | 'AVP_AP9440GYT-HF.pdf'           | ''            | ''     | ''  | ''         | ''      | '20121115'
 'BSZ160N10NS3G'   | 'SMLF'    | 'IC'     | 'BAM160N0000'(!) = 'End of Design' | 'Comp-Approve' | 'BAM160N0000' |'TSDSON8XA'| 'TRANS MOSF BSZ160N10NS3 G(100V,40A,2.1W)' | 'SNI'   | 'BSZ160N10NS3 G'  | 'EP(V1)'     | ''        | 'IC'  | ''      | ''     | 'T2L-JIACHENG'  | 'BSZ160N10N3SG_rev-2.pdf'        | ''            | ''     | ''  | ''         | ''      | '20121126'
 'BSZ160N10NS3G'   | 'SMLF'    | 'EMPTY'  | 'BAM160N0000'(!) = 'End of Design' | 'Comp-Approve' | 'BAM160N0000' |'TSDSON8XA'| 'TRANS MOSF BSZ160N10NS3 G(100V,40A,2.1W)' | 'SNI'   | 'BSZ160N10NS3 G'  | 'EP(V1)'     | ''        | 'IC'  | ''      | ''     | 'T2L-JIACHENG'  | 'BSZ160N10N3SG_rev-2.pdf'        | ''            | ''     | ''  | ''         | ''      | '20121126'
 'AP9424GYTHF'     | 'SMLF'    | 'IC'     | 'BAM94240000'(!) = ''              | 'End of Life'  | 'BAM94240000' |'PMPAK5_3_EOL'| 'TRANS MOSFET AP9424GYT-HF(30V,18A,3.57W)' | 'AVP'   | 'AP9424GYT-HF'    | 'EP(V1)'     | 'EP(V1)'  | 'IC'  | ''      | ''     | 'T6M-YVETTE'    | 'AVP_AP9424GYT-HF.pdf'           | ''            | ''     | ''  | ''         | ''      | '20121204'
 'AP9424GYTHF'     | 'SMLF'    | 'EMPTY'  | 'BAM94240000'(!) = ''              | 'End of Life'  | 'BAM94240000' |'PMPAK5_3_EOL'| 'TRANS MOSFET AP9424GYT-HF(30V,18A,3.57W)' | 'AVP'   | 'AP9424GYT-HF'    | 'EP(V1)'     | 'EP(V1)'  | 'IC'  | ''      | ''     | 'T6M-YVETTE'    | 'AVP_AP9424GYT-HF.pdf'           | ''            | ''     | ''  | ''         | ''      | '20121204'
 'CSD16321Q5'      | 'SMLF'    | 'IC'     | 'BAM16320000'(!) = ''              | ''             | 'BAM16320000' |'SON5_THXA'| 'TRAN MOS CSD16321Q5(25V,100A)QFN5X6 3.1W' | 'CSD'   | 'CSD16321Q5'      | 'EP(V1)'     | 'EP(V1)'  | 'IC'  | ''      | ''     | 'S2S-SUNNY'     | 'CSD_CSD16321Q5.pdf'             | ''            | ''     | ''  | ''         | ''      | '20131021'
 'CSD16321Q5'      | 'SMLF'    | 'EMPTY'  | 'BAM16320000'(!) = ''              | ''             | 'BAM16320000' |'SON5_THXA'| 'TRAN MOS CSD16321Q5(25V,100A)QFN5X6 3.1W' | 'CSD'   | 'CSD16321Q5'      | 'EP(V1)'     | 'EP(V1)'  | 'IC'  | ''      | ''     | 'S2S-SUNNY'     | 'CSD_CSD16321Q5.pdf'             | ''            | ''     | ''  | ''         | ''      | '20131021'
 'CSD16322Q5'      | 'SMLF'    | 'IC'     | 'BAM16320002'(!) = ''              | ''             | 'BAM16320002' |'SON5_THXA'| 'TRAN MOS CSD16322Q5 (25V, 97A,3.1W) SON'  | 'TIC'   | 'CSD16322Q5'      | 'EP(V1)'     | 'EP(V1)'  | 'IC'  | ''      | ''     | 'S2S-SUNNY'     | 'TIC_CSD16322Q5.pdf'             | ''            | ''     | ''  | ''         | ''      | '20131021'
 'CSD16322Q5'      | 'SMLF'    | 'EMPTY'  | 'BAM16320002'(!) = ''              | ''             | 'BAM16320002' |'SON5_THXA'| 'TRAN MOS CSD16322Q5 (25V, 97A,3.1W) SON'  | 'TIC'   | 'CSD16322Q5'      | 'EP(V1)'     | 'EP(V1)'  | 'IC'  | ''      | ''     | 'S2S-SUNNY'     | 'TIC_CSD16322Q5.pdf'             | ''            | ''     | ''  | ''         | ''      | '20131021'
 'CSD17556Q5B'     | 'SMLF'    | 'IC'     | 'BAM17550000'(!) = ''              | ''             | 'BAM17550000' |'SOIC8_PWXJ'| 'TRANS MOS CSD17556Q5B(30V,100A,3.1W)'     | 'TIC'   | 'CSD17556Q5B'     | 'EP(V1)'     | ''        | 'IC'  | ''      | ''     | 'MF1-EDDIE'     | 'TIC_CSD17556Q5B.pdf'            | ''            | ''     | ''  | ''         | ''      | '20131129'
 'CSD17556Q5B'     | 'SMLF'    | 'EMPTY'  | 'BAM17550000'(!) = ''              | ''             | 'BAM17550000' |'SOIC8_PWXJ'| 'TRANS MOS CSD17556Q5B(30V,100A,3.1W)'     | 'TIC'   | 'CSD17556Q5B'     | 'EP(V1)'     | ''        | 'IC'  | ''      | ''     | 'MF1-EDDIE'     | 'TIC_CSD17556Q5B.pdf'            | ''            | ''     | ''  | ''         | ''      | '20131129'
 'PSMN013-100YSE'  | 'SMLF'    | 'IC'     | 'BAM31000000'(!) = ''              | ''             | 'BAM31000000' |'SOT1023'| 'TRANS MOS PSMN013-100YSE(100V,58A,238W)'  | 'NXP'   | 'PSMN013-100YSE'  | 'EP(V1)'     | ''        | 'IC'  | ''      | ''     | 'MF1R-DENNY'    | 'NXP_PSMN013-100YSE_rev2012.pdf' | ''            | ''     | ''  | ''         | ''      | '20140127'
 'PSMN013-100YSE'  | 'SMLF'    | 'EMPTY'  | 'BAM31000000'(!) = ''              | ''             | 'BAM31000000' |'SOT1023'| 'TRANS MOS PSMN013-100YSE(100V,58A,238W)'  | 'NXP'   | 'PSMN013-100YSE'  | 'EP(V1)'     | ''        | 'IC'  | ''      | ''     | 'MF1R-DENNY'    | 'NXP_PSMN013-100YSE_rev2012.pdf' | ''            | ''     | ''  | ''         | ''      | '20140127'
 'FDMS86255'       | 'SMLF'    | 'IC'     | 'BAM62550000'(!) = ''              | ''             | 'BAM62550000' |'POWER56_1-27_5X6-075'| 'TRANS MOS FDMS86255(10A,150V,2.7W)'       | 'FAC'   | 'FDMS86255'       | 'EP(V1)'     | 'EP(V1)'  | 'IC'  | ''      | ''     | 'T2H-GAVEN'     | 'FAC_FDMS86255_REVC4.pdf'        | ''            | ''     | ''  | ''         | ''      | '20140801'
 'FDMS86255'       | 'SMLF'    | 'EMPTY'  | 'BAM62550000'(!) = ''              | ''             | 'BAM62550000' |'POWER56_1-27_5X6-075'| 'TRANS MOS FDMS86255(10A,150V,2.7W)'       | 'FAC'   | 'FDMS86255'       | 'EP(V1)'     | 'EP(V1)'  | 'IC'  | ''      | ''     | 'T2H-GAVEN'     | 'FAC_FDMS86255_REVC4.pdf'        | ''            | ''     | ''  | ''         | ''      | '20140801'
 'CSD18532Q5B'     | 'SMLF'    | 'IC'     | 'BAM18530000'(!) = ''              | ''             | 'BAM18530000' |'SON8XA'| 'TRANS MOS CSD18532Q5B(23A,60V,3.2W)'      | 'TIC'   | 'CSD18532Q5B'     | 'EP(V1)'     | 'EP(V1)'  | 'IC'  | ''      | ''     | 'T2H-GAVEN'     | 'TIC_CSD18532Q5B.pdf'            | ''            | ''     | ''  | ''         | ''      | '20140808'
 'CSD18532Q5B'     | 'SMLF'    | 'EMPTY'  | 'BAM18530000'(!) = ''              | ''             | 'BAM18530000' |'SON8XA'| 'TRANS MOS CSD18532Q5B(23A,60V,3.2W)'      | 'TIC'   | 'CSD18532Q5B'     | 'EP(V1)'     | 'EP(V1)'  | 'IC'  | ''      | ''     | 'T2H-GAVEN'     | 'TIC_CSD18532Q5B.pdf'            | ''            | ''     | ''  | ''         | ''      | '20140808'
 'PSMN0R7-25YLD'   | 'SMLF'    | 'IC'     | 'BAM0R725000'(!) = ''              | ''             | 'BAM0R725000' |'SOT1023'| 'TRANS MOSFET PSMN0R7(25V,100A,290W)'      | 'NXP'   | 'PSMN0R7-25YLD'   | 'EU(V1)'     | ''        | 'IC'  | ''      | ''     | 'S3E-DEREK'     | 'NXP_PSMN0R7-25YLD.pdf'          | ''            | ''     | ''  | ''         | ''      | '20150424'
 'PSMN0R7-25YLD'   | 'SMLF'    | 'EMPTY'  | 'BAM0R725000'(!) = ''              | ''             | 'BAM0R725000' |'SOT1023'| 'TRANS MOSFET PSMN0R7(25V,100A,290W)'      | 'NXP'   | 'PSMN0R7-25YLD'   | 'EU(V1)'     | ''        | 'IC'  | ''      | ''     | 'S3E-DEREK'     | 'NXP_PSMN0R7-25YLD.pdf'          | ''            | ''     | ''  | ''         | ''      | '20150424'
 'PSMN0R9-30YLD'   | 'SMLF'    | 'IC'     | 'BAM30YLD000'(!) = ''              | ''             | 'BAM30YLD000' |'SOT1023'| 'TRANS MOS PSMN0R9-30YLD(30V,100A,349W)'   | 'NXP'   | 'PSMN0R9-30YLD'   | 'EP(V1)'     | ''        | 'IC'  | ''      | ''     | 'T2HV-MARK'     | 'NXP_PSMN0R9-30YLD.pdf'          | ''            | ''     | ''  | ''         | ''      | '20160408'
 'PSMN0R9-30YLD'   | 'SMLF'    | 'EMPTY'  | 'BAM30YLD000'(!) = ''              | ''             | 'BAM30YLD000' |'SOT1023'| 'TRANS MOS PSMN0R9-30YLD(30V,100A,349W)'   | 'NXP'   | 'PSMN0R9-30YLD'   | 'EP(V1)'     | ''        | 'IC'  | ''      | ''     | 'T2HV-MARK'     | 'NXP_PSMN0R9-30YLD.pdf'          | ''            | ''     | ''  | ''         | ''      | '20160408'
 'PSMN1R3-30YL'    | 'SMLF'    | 'IC'     | 'BAM1R330000'(!) = ''              | ''             | 'BAM1R330000' |'SOT1023'| 'TRANS MOS PSMN1R3-30YL(20V,100A,121W)'    | 'NXP'   | 'PSMN1R3-30YL'    | 'EP(V1)'     | ''        | 'IC'  | ''      | ''     | 'JG1-JOHN'      | 'NXP_PSMN1R3-30YL.pdf'           | ''            | ''     | ''  | ''         | ''      | '20160705'
 'PSMN1R3-30YL'    | 'SMLF'    | 'EMPTY'  | 'BAM1R330000'(!) = ''              | ''             | 'BAM1R330000' |'SOT1023'| 'TRANS MOS PSMN1R3-30YL(20V,100A,121W)'    | 'NXP'   | 'PSMN1R3-30YL'    | 'EP(V1)'     | ''        | 'IC'  | ''      | ''     | 'JG1-JOHN'      | 'NXP_PSMN1R3-30YL.pdf'           | ''            | ''     | ''  | ''         | ''      | '20160705'
 'AON7508'         | 'SMLF'    | 'IC'     | 'BAM75080000'(!) = ''              | ''             | 'BAM75080000' |'DFN4_TH'| 'TRANS MOS AON7508(30V,32A,3.1W)'          | 'AOS'   | 'AON7508'         | 'EP(V1)'     | 'EP(V1)'  | 'IC'  | ''      | ''     | 'F08-ALEN'      | 'AOS_AON7508_rev2015-11-19.pdf'  | ''            | ''     | ''  | ''         | ''      | '20161011'
 'AON7508'         | 'SMLF'    | 'EMPTY'  | 'BAM75080000'(!) = ''              | ''             | 'BAM75080000' |'DFN4_TH'| 'TRANS MOS AON7508(30V,32A,3.1W)'          | 'AOS'   | 'AON7508'         | 'EP(V1)'     | 'EP(V1)'  | 'IC'  | ''      | ''     | 'F08-ALEN'      | 'AOS_AON7508_rev2015-11-19.pdf'  | ''            | ''     | ''  | ''         | ''      | '20161011'
 'NTMFS4H01NT1G'   | 'SMLF'    | 'IC'     | 'BAM4H010000'(!) = ''              | 'End of Life'    | 'BAM4H010000' |'DFN5_TH_4-9X5-9_EOL'| 'TRANS MOS NTMFS4H01NT1G(25V,54A,3.2W)'    | 'ONS'   | 'NTMFS4H01NT1G'   | 'EP(V1)'     | 'EP(V1)'  | 'IC'  | ''      | ''     | 'JG1-UNIS'      | 'ONS_NTMFS4H01NT3G.pdf'          | ''            | ''     | ''  | ''         | ''      | '20160224'
 'NTMFS4H01NT1G'   | 'SMLF'    | 'EMPTY'  | 'BAM4H010000'(!) = ''              | 'End of Life'    | 'BAM4H010000' |'DFN5_TH_4-9X5-9_EOL'| 'TRANS MOS NTMFS4H01NT1G(25V,54A,3.2W)'    | 'ONS'   | 'NTMFS4H01NT1G'   | 'EP(V1)'     | 'EP(V1)'  | 'IC'  | ''      | ''     | 'JG1-UNIS'      | 'ONS_NTMFS4H01NT3G.pdf'          | ''            | ''     | ''  | ''         | ''      | '20160224'
 'PSMN0R9-25YLC'   | 'SMLF'    | 'IC'     | 'BAM0R925000'(!) = ''              | ''             | 'BAM0R925000' |'LFPAK5_1-27_4-9X3-95'| 'TRANS MOSFET PSMN1(25V,100A,137W)SOT669'  | 'NXP'   | 'PSMN0R9-25YLC'   | 'EP(V1)'     | 'EP(V1)'  | 'IC'  | ''      | ''     | 'CAVIUM-MARCUS' | 'NXP_PSMN0R9-25YLC.pdf'          | ''            | ''     | ''  | ''         | ''      | '20170331'
 'PSMN0R9-25YLC'   | 'SMLF'    | 'EMPTY'  | 'BAM0R925000'(!) = ''              | ''             | 'BAM0R925000' |'LFPAK5_1-27_4-9X3-95'| 'TRANS MOSFET PSMN1(25V,100A,137W)SOT669'  | 'NXP'   | 'PSMN0R9-25YLC'   | 'EP(V1)'     | 'EP(V1)'  | 'IC'  | ''      | ''     | 'CAVIUM-MARCUS' | 'NXP_PSMN0R9-25YLC.pdf'          | ''            | ''     | ''  | ''         | ''      | '20170331'
 'PSMNR70-30YLH'   | 'SMLF'    | 'IC'     | 'BAMNR700000'(!) = ''              | ''             | 'BAMNR700000' |'LFPAK5_1-27_4-9X3-95'| 'TRANS MOS PSMNR70-30YLH(30V,300A,268W)'   | 'NXE'   | 'PSMNR70-30YLH'   | 'EP(V1)'     | ''        | 'IC'  | ''      | ''     | 'F09C-LUKE'     | 'NXE_PSMNR70-30YLH.pdf'          | ''            | ''     | ''  | ''         | ''      | '20190223'
 'PSMNR70-30YLH'   | 'SMLF'    | 'EMPTY'  | 'BAMNR700000'(!) = ''              | ''             | 'BAMNR700000' |'LFPAK5_1-27_4-9X3-95'| 'TRANS MOS PSMNR70-30YLH(30V,300A,268W)'   | 'NXE'   | 'PSMNR70-30YLH'   | 'EP(V1)'     | ''        | 'IC'  | ''      | ''     | 'F09C-LUKE'     | 'NXE_PSMNR70-30YLH.pdf'          | ''            | ''     | ''  | ''         | ''      | '20190223'
 'PSMNR51-25YLH'   | 'SMLF'    | 'IC'     | 'BAMNR510000'(!) = ''              | ''             | 'BAMNR510000' |'SOT1023'| 'TRANS MOS PSMNR51-25YLH(25V,380A,333W)'   | 'NXE'   | 'PSMNR51-25YLH'   | 'EP(V1)'     | ''        | 'IC'  | ''      | ''     | 'S5Z-MIKE'      | 'NXE_PSMNR51-25YLH.pdf'          | ''            | ''     | ''  | ''         | ''      | '20190416'
 'PSMNR51-25YLH'   | 'SMLF'    | 'EMPTY'  | 'BAMNR510000'(!) = ''              | ''             | 'BAMNR510000' |'SOT1023'| 'TRANS MOS PSMNR51-25YLH(25V,380A,333W)'   | 'NXE'   | 'PSMNR51-25YLH'   | 'EP(V1)'     | ''        | 'IC'  | ''      | ''     | 'S5Z-MIKE'      | 'NXE_PSMNR51-25YLH.pdf'          | ''            | ''     | ''  | ''         | ''      | '20190416'
 'PSMNR58-30YLH'   | 'SMLF'    | 'IC'     | 'BAMNR580000'(!) = ''              | ''             | 'BAMNR580000' |'SOT1023'| 'TRANS MOS PSMNR58-30YLH(30V,380A,333W)'   | 'NXE'   | 'PSMNR58-30YLH'   | 'EP(V1)'     | ''        | 'IC'  | ''      | ''     | 'S5Z-MIKE'      | 'NXE_PSMNR58-30YLH.pdf'          | ''            | ''     | ''  | ''         | ''      | '20190423'
 'PSMNR58-30YLH'   | 'SMLF'    | 'EMPTY'  | 'BAMNR580000'(!) = ''              | ''             | 'BAMNR580000' |'SOT1023'| 'TRANS MOS PSMNR58-30YLH(30V,380A,333W)'   | 'NXE'   | 'PSMNR58-30YLH'   | 'EP(V1)'     | ''        | 'IC'  | ''      | ''     | 'S5Z-MIKE'      | 'NXE_PSMNR58-30YLH.pdf'          | ''            | ''     | ''  | ''         | ''      | '20190423'
 'CSD16407Q5C'     | 'SMLF'    | 'IC'     | 'BAM16400004'(!) = ''              | ''             | 'BAM16400004' |'SON5_THXA'| 'TRANS MOS CSD16407Q5C(25V,100A,3.1W)'     | 'TIC'   | 'CSD16407Q5C'     | 'EP(V1)'     | ''        | 'IC'  | ''      | ''     | 'F09B-GREG'     | 'TIC_CSD16407Q5C.pdf'            | ''            | ''     | ''  | ''         | ''      | '20190604'
 'CSD16407Q5C'     | 'SMLF'    | 'EMPTY'  | 'BAM16400004'(!) = ''              | ''             | 'BAM16400004' |'SON5_THXA'| 'TRANS MOS CSD16407Q5C(25V,100A,3.1W)'     | 'TIC'   | 'CSD16407Q5C'     | 'EP(V1)'     | ''        | 'IC'  | ''      | ''     | 'F09B-GREG'     | 'TIC_CSD16407Q5C.pdf'            | ''            | ''     | ''  | ''         | ''      | '20190604'
 'PSMN7R0-30YLC'   | 'SMLF'    | 'IC'     | 'BAMN7R00000'(!) = ''              | ''             | 'BAMN7R00000' |'LFPAK5_1-27_4-9X3-95'| 'TRANS MOS PSMN7R0-30YLC(30V,61A,48W)'     | 'NXE'   | 'PSMN7R0-30YLC'   | 'EP(V1)'     | ''        | 'IC'  | ''      | ''     | 'F0C-ALEN'      | 'NXE_PSMN7R0-30YLC.pdf'          | ''            | ''     | ''  | ''         | ''      | '20190625'
 'PSMN7R0-30YLC'   | 'SMLF'    | 'EMPTY'  | 'BAMN7R00000'(!) = ''              | ''             | 'BAMN7R00000' |'LFPAK5_1-27_4-9X3-95'| 'TRANS MOS PSMN7R0-30YLC(30V,61A,48W)'     | 'NXE'   | 'PSMN7R0-30YLC'   | 'EP(V1)'     | ''        | 'IC'  | ''      | ''     | 'F0C-ALEN'      | 'NXE_PSMN7R0-30YLC.pdf'          | ''            | ''     | ''  | ''         | ''      | '20190625'
 'NTMFS5C628NLT1G' | 'SMLF'    | 'IC'     | 'BAM06280000'(!) = ''              | ''             | 'BAM06280000' |'DFN5_TH_4-9X5-9'| 'TRANS MOS NTMFS5C628NLT1G(60V,150A,110W)' | 'ONS'   | 'NTMFS5C628NLT1G' | 'EP(V1)'     | 'EP(V1)'  | 'IC'  | ''      | ''     | 'S8I-JW'        | 'ONS_NTMFS5C628NLT1G.pdf'        | ''            | ''     | ''  | ''         | ''      | '20191003'
 'NTMFS5C628NLT1G' | 'SMLF'    | 'EMPTY'  | 'BAM06280000'(!) = ''              | ''             | 'BAM06280000' |'DFN5_TH_4-9X5-9'| 'TRANS MOS NTMFS5C628NLT1G(60V,150A,110W)' | 'ONS'   | 'NTMFS5C628NLT1G' | 'EP(V1)'     | 'EP(V1)'  | 'IC'  | ''      | ''     | 'S8I-JW'        | 'ONS_NTMFS5C628NLT1G.pdf'        | ''            | ''     | ''  | ''         | ''      | '20191003'
 'PSMN1R6-30MLH'   | 'SMLF'    | 'IC'     | 'BAM1R630000'(!) = ''              | ''             | 'BAM1R630000' |'LFPAK33-5_0-65_3-3X2-6'| 'TRANS MOS PSMN1R6-30MLH(30V,160A,106W)'   | 'NXE'   | 'PSMN1R6-30MLH'   | 'EP(V1)'     | ''        | 'IC'  | ''      | ''     | 'IXH-JOHNNY'    | 'NXE_PSMN1R6-30MLH.pdf'          | ''            | ''     | ''  | ''         | ''      | '20210217'
 'PSMN1R6-30MLH'   | 'SMLF'    | 'EMPTY'  | 'BAM1R630000'(!) = ''              | ''             | 'BAM1R630000' |'LFPAK33-5_0-65_3-3X2-6'| 'TRANS MOS PSMN1R6-30MLH(30V,160A,106W)'   | 'NXE'   | 'PSMN1R6-30MLH'   | 'EP(V1)'     | ''        | 'IC'  | ''      | ''     | 'IXH-JOHNNY'    | 'NXE_PSMN1R6-30MLH.pdf'          | ''            | ''     | ''  | ''         | ''      | '20210217'
 'PSMN040-100MSE'  | 'SMLF'    | 'IC'     | 'BAM01000006'(!) = ''              | ''             | 'BAM01000006' |'LFPAK33-5_0-65_3-3X2-6'| 'TRANS MOSFET PSMN040(100V,30A,91W)'       | 'NXE'   | 'PSMN040-100MSE'  | 'EP(V1)'     | 'EP(V1)'  | 'IC'  | ''      | ''     | 'P0A-STEVE'     | 'NXE_PSMN040-100MSE.pdf'         | ''            | ''     | ''  | ''         | ''      | '20210309'
 'PSMN040-100MSE'  | 'SMLF'    | 'EMPTY'  | 'BAM01000006'(!) = ''              | ''             | 'BAM01000006' |'LFPAK33-5_0-65_3-3X2-6'| 'TRANS MOSFET PSMN040(100V,30A,91W)'       | 'NXE'   | 'PSMN040-100MSE'  | 'EP(V1)'     | 'EP(V1)'  | 'IC'  | ''      | ''     | 'P0A-STEVE'     | 'NXE_PSMN040-100MSE.pdf'         | ''            | ''     | ''  | ''         | ''      | '20210309'
 'PSMN2R0-25MLD'   | 'SMLF'    | 'IC'     | 'BAMN2R00002'(!) = ''              | ''             | 'BAMN2R00002' |'LFPAK33-5_0-65_3-3X2-6'| 'TRANS MOS PSMN2R0-25MLD(25V,70A,74W)'     | 'NXE'   | 'PSMN2R0-25MLD'   | 'EP(V1)'     | ''        | 'IC'  | ''      | ''     | 'S9T-ANDY'      | 'NXE_PSMN2R0-25MLD.pdf'          | ''            | ''     | ''  | ''         | ''      | '20210323'
 'PSMN2R0-25MLD'   | 'SMLF'    | 'EMPTY'  | 'BAMN2R00002'(!) = ''              | ''             | 'BAMN2R00002' |'LFPAK33-5_0-65_3-3X2-6'| 'TRANS MOS PSMN2R0-25MLD(25V,70A,74W)'     | 'NXE'   | 'PSMN2R0-25MLD'   | 'EP(V1)'     | ''        | 'IC'  | ''      | ''     | 'S9T-ANDY'      | 'NXE_PSMN2R0-25MLD.pdf'          | ''            | ''     | ''  | ''         | ''      | '20210323'
 'PSMN2R4-30MLD'   | 'SMLF'    | 'IC'     | 'BAM30ML0000'(!) = ''              | ''               | 'BAM30ML0000' |'LFPAK33-5_0-65_3-3X2-6'| 'TRANS MOS PSMN2R4-30MLD(30V,70A,91W)'     | 'NXE'   | 'PSMN2R4-30MLD'   | 'EP(V1)'     | ''        | 'IC'  | ''      | ''     | 'S9T-ANDY'      | 'NXE_PSMN2R4-30MLD.pdf'          | ''            | ''     | ''  | ''         | ''      | '20210330'
 'PSMN2R4-30MLD'   | 'SMLF'    | 'EMPTY'  | 'BAM30ML0000'(!) = ''              | ''               | 'BAM30ML0000' |'LFPAK33-5_0-65_3-3X2-6'| 'TRANS MOS PSMN2R4-30MLD(30V,70A,91W)'     | 'NXE'   | 'PSMN2R4-30MLD'   | 'EP(V1)'     | ''        | 'IC'  | ''      | ''     | 'S9T-ANDY'      | 'NXE_PSMN2R4-30MLD.pdf'          | ''            | ''     | ''  | ''         | ''      | '20210330'

END_PART

END.

